# T6G (Grand Teton) — schematic netlist excerpt (pin names and nets, part order shuffled) for the footprints in the layout excerpt that follows; sources: Cadence DE-HDL packaged netlist, KiCad conversion of 04192023_DAF0TMB3IC0_F0TG_MB_C_brd_V02_OCP.brd

PR8007  Q_RES  0 5% CHIP  pkg 0402LF  page 200 : A = SVID_PVDDCR_CPU1_P0_SVC_R ; B = SVID_PVDDCR_CPU1_P0_SVC_R1

U9051  74LVC1G08W57  74LVC1G08W5-7 IC  pkg SOT25-5_0-95_3X1-6  page 142
  A  = OCP_V3_2_P3V3_PWRGD
  B  = HP_LVC3_OCP_V3_2_P12V_PWRGD_R2
  GND  = GND
  Y  = HP_LVC3_OCP_V3_2_PWRGD_R2
  VCC  = P3V3_AUX

(kicad_pcb
	(version 20260206)
	(generator "pcbnew")
	(generator_version "10.0")
	(general
		(thickness 1.6)
		(legacy_teardrops no)
	)
	(paper "A4")
	(title_block
		(title "04192023_DAF0TMB3IC0_F0TG_MB_C_brd_V02_OCP.brd")
		(comment 1 "Grand Teton / footprints 2378-2379 of 8354")
	)
	(layers
		(0 "F.Cu" signal "TOP")
		(4 "In1.Cu" signal "GND")
		(6 "In2.Cu" signal "IN1")
		(8 "In3.Cu" signal "GND1")
		(10 "In4.Cu" signal "IN2")
		(12 "In5.Cu" signal "GND2")
		(14 "In6.Cu" signal "IN3")
		(16 "In7.Cu" signal "GND3")
		(18 "In8.Cu" signal "VCC")
		(20 "In9.Cu" signal "VCC1")
		(22 "In10.Cu" signal "GND4")
		(24 "In11.Cu" signal "IN4")
		(26 "In12.Cu" signal "GND5")
		(28 "In13.Cu" signal "IN5")
		(30 "In14.Cu" signal "GND6")
		(32 "In15.Cu" signal "IN6")
		(34 "In16.Cu" signal "GND7")
		(2 "B.Cu" signal "BOTTOM")
		(9 "F.Adhes" user "F.Adhesive")
		(11 "B.Adhes" user "B.Adhesive")
		(13 "F.Paste" user "Package Geometry/Pastemask Top")
		(15 "B.Paste" user "Package Geometry/Pastemask Bottom")
		(5 "F.SilkS" user "Ref Des/Silkscreen Top")
		(7 "B.SilkS" user "Ref Des/Silkscreen Bottom")
		(1 "F.Mask" user "Board Geometry/Soldermask Top")
		(3 "B.Mask" user "Board Geometry/Soldermask Bottom")
		(17 "Dwgs.User" user "User.Drawings")
		(19 "Cmts.User" user "User.Comments")
		(21 "Eco1.User" user "User.Eco1")
		(23 "Eco2.User" user "User.Eco2")
		(25 "Edge.Cuts" user "Board Geometry/Outline")
		(27 "Margin" user)
		(31 "F.CrtYd" user "Package Geometry/Place Bound Top")
		(29 "B.CrtYd" user "Package Geometry/Place Bound Bottom")
		(35 "F.Fab" user "Ref Des/Assembly Top")
		(33 "B.Fab" user "Ref Des/Assembly Bottom")
	)
	(footprint ""
		(layer "F.Cu")
		(at 62.339728 -53.693314)
		(property "Reference" "U9051"
			(at -4.14782 2.455672 0)
			(unlocked yes)
			(layer "F.SilkS")
			(effects
				(font
					(size 0.7874 0.5842)
					(thickness 0.1524)
				)
				(justify left)
			)
		)
		(property "Value" ""
			(at 0 0 0)
			(layer "F.Fab")
			(effects
				(font
					(size 1.27 1.27)
				)
			)
		)
		(duplicate_pad_numbers_are_jumpers no)
		(fp_line
			(start -1.733296 -1.549908)
			(end -1.733296 1.549908)
			(stroke
				(width 0.1524)
				(type default)
			)
			(layer "F.SilkS")
		)
		(fp_line
			(start -1.733296 1.549908)
			(end 1.733296 1.549908)
			(stroke
				(width 0.1524)
				(type default)
			)
			(layer "F.SilkS")
		)
		(fp_line
			(start -0.660908 -1.549908)
			(end -1.733296 -1.549908)
			(stroke
				(width 0.1524)
				(type default)
			)
			(layer "F.SilkS")
		)
		(fp_line
			(start 0 -0.889)
			(end -0.660908 -1.549908)
			(stroke
				(width 0.1524)
				(type default)
			)
			(layer "F.SilkS")
		)
		(fp_line
			(start 0.660908 -1.549908)
			(end 0 -0.889)
			(stroke
				(width 0.1524)
				(type default)
			)
			(layer "F.SilkS")
		)
		(fp_line
			(start 1.733296 -1.549908)
			(end 0.660908 -1.549908)
			(stroke
				(width 0.1524)
				(type default)
			)
			(layer "F.SilkS")
		)
		(fp_line
			(start 1.733296 1.549908)
			(end 1.733296 -1.549908)
			(stroke
				(width 0.1524)
				(type default)
			)
			(layer "F.SilkS")
		)
		(fp_poly
			(pts
				(xy -2.4384 -1.20396) (xy -2.4384 -0.69596) (xy -1.9304 -0.94996)
			)
			(stroke
				(width 0)
				(type default)
			)
			(fill yes)
			(layer "F.SilkS")
		)
		(fp_line
			(start -0.849884 -1.549908)
			(end -0.849884 1.549908)
			(stroke
				(width 0.1)
				(type default)
			)
			(layer "F.Fab")
		)
		(fp_line
			(start -0.849884 1.549908)
			(end 0.849884 1.549908)
			(stroke
				(width 0.1)
				(type default)
			)
			(layer "F.Fab")
		)
		(fp_line
			(start 0.849884 -1.549908)
			(end -0.849884 -1.549908)
			(stroke
				(width 0.1)
				(type default)
			)
			(layer "F.Fab")
		)
		(fp_line
			(start 0.849884 1.549908)
			(end 0.849884 -1.549908)
			(stroke
				(width 0.1)
				(type default)
			)
			(layer "F.Fab")
		)
		(fp_poly
			(pts
				(xy -2.4384 -1.20396) (xy -2.4384 -0.69596) (xy -1.9304 -0.94996)
			)
			(stroke
				(width 0)
				(type default)
			)
			(fill yes)
			(layer "F.Fab")
		)
		(pad "1" smd rect
			(at -1.199896 -0.94996 270)
			(size 0.5588 0.8128)
			(layers "F.Cu" "F.Mask" "F.Paste")
			(net "OCP_V3_2_P3V3_PWRGD")
		)
		(pad "2" smd rect
			(at -1.199896 0 270)
			(size 0.5588 0.8128)
			(layers "F.Cu" "F.Mask" "F.Paste")
			(net "HP_LVC3_OCP_V3_2_P12V_PWRGD_R2")
		)
		(pad "3" smd rect
			(at -1.199896 0.94996 270)
			(size 0.5588 0.8128)
			(layers "F.Cu" "F.Mask" "F.Paste")
			(net "GND")
		)
		(pad "4" smd rect
			(at 1.199896 0.94996 270)
			(size 0.5588 0.8128)
			(layers "F.Cu" "F.Mask" "F.Paste")
			(net "HP_LVC3_OCP_V3_2_PWRGD_R2")
		)
		(pad "5" smd rect
			(at 1.199896 -0.94996 270)
			(size 0.5588 0.8128)
			(layers "F.Cu" "F.Mask" "F.Paste")
			(net "P3V3_AUX")
		)
	)
	(footprint ""
		(layer "F.Cu")
		(at 304.419 -356.997)
		(property "Reference" "PR8007"
			(at 0 0 0)
			(layer "F.SilkS")
			(hide yes)
			(effects
				(font
					(size 1.27 1.27)
				)
			)
		)
		(property "Value" ""
			(at 0 0 0)
			(layer "F.Fab")
			(effects
				(font
					(size 1.27 1.27)
				)
			)
		)
		(duplicate_pad_numbers_are_jumpers no)
		(fp_line
			(start -0.7874 -0.4064)
			(end 0.7874 -0.4064)
			(stroke
				(width 0.1524)
				(type default)
			)
			(layer "F.SilkS")
		)
		(fp_line
			(start -0.7874 0.4064)
			(end -0.7874 -0.4064)
			(stroke
				(width 0.1524)
				(type default)
			)
			(layer "F.SilkS")
		)
		(fp_line
			(start 0.7874 -0.4064)
			(end 0.7874 0.4064)
			(stroke
				(width 0.1524)
				(type default)
			)
			(layer "F.SilkS")
		)
		(fp_line
			(start 0.7874 0.4064)
			(end -0.7874 0.4064)
			(stroke
				(width 0.1524)
				(type default)
			)
			(layer "F.SilkS")
		)
		(fp_line
			(start -0.67945 -0.305054)
			(end -0.12065 -0.305054)
			(stroke
				(width 0.1)
				(type default)
			)
			(layer "F.Fab")
		)
		(fp_line
			(start -0.67945 0.3048)
			(end -0.67945 -0.305054)
			(stroke
				(width 0.1)
				(type default)
			)
			(layer "F.Fab")
		)
		(fp_line
			(start -0.12065 -0.305054)
			(end -0.12065 -0.2794)
			(stroke
				(width 0.1)
				(type default)
			)
			(layer "F.Fab")
		)
		(fp_line
			(start -0.12065 -0.2794)
			(end 0.12065 -0.2794)
			(stroke
				(width 0.1)
				(type default)
			)
			(layer "F.Fab")
		)
		(fp_line
			(start -0.12065 0.2794)
			(end -0.12065 0.3048)
			(stroke
				(width 0.1)
				(type default)
			)
			(layer "F.Fab")
		)
		(fp_line
			(start -0.12065 0.3048)
			(end -0.67945 0.3048)
			(stroke
				(width 0.1)
				(type default)
			)
			(layer "F.Fab")
		)
		(fp_line
			(start 0.120396 0.2794)
			(end -0.12065 0.2794)
			(stroke
				(width 0.1)
				(type default)
			)
			(layer "F.Fab")
		)
		(fp_line
			(start 0.120396 0.3048)
			(end 0.120396 0.2794)
			(stroke
				(width 0.1)
				(type default)
			)
			(layer "F.Fab")
		)
		(fp_line
			(start 0.12065 -0.3048)
			(end 0.67945 -0.3048)
			(stroke
				(width 0.1)
				(type default)
			)
			(layer "F.Fab")
		)
		(fp_line
			(start 0.12065 -0.2794)
			(end 0.12065 -0.3048)
			(stroke
				(width 0.1)
				(type default)
			)
			(layer "F.Fab")
		)
		(fp_line
			(start 0.67945 -0.3048)
			(end 0.67945 0.3048)
			(stroke
				(width 0.1)
				(type default)
			)
			(layer "F.Fab")
		)
		(fp_line
			(start 0.67945 0.3048)
			(end 0.120396 0.3048)
			(stroke
				(width 0.1)
				(type default)
			)
			(layer "F.Fab")
		)
		(pad "1" smd circle
			(at -0.40005 0)
			(size 0 0)
			(layers "F.Cu" "F.Mask" "F.Paste")
			(net "SVID_PVDDCR_CPU1_P0_SVC_R")
		)
		(pad "2" smd circle
			(at 0.40005 0)
			(size 0 0)
			(layers "F.Cu" "F.Mask" "F.Paste")
			(net "SVID_PVDDCR_CPU1_P0_SVC_R1")
		)
	)
)
